(kicad_pcb
	(version 20260206)
	(generator "pcbnew")
	(generator_version "10.0")
	(general
		(thickness 1.6)
		(legacy_teardrops no)
	)
	(paper "A4")
	(title_block
		(title "01162023_DA0F0TEBIF0_F0T_Expander_BD_F_brd_V02_OCP.brd")
		(comment 1 "Grand Teton / footprints 4322-4328 of 9728")
	)
	(layers
		(0 "F.Cu" signal "TOP")
		(4 "In1.Cu" signal "GND")
		(6 "In2.Cu" signal "VCC")
		(8 "In3.Cu" signal "VCC1")
		(10 "In4.Cu" signal "GND1")
		(12 "In5.Cu" signal "IN1")
		(14 "In6.Cu" signal "GND2")
		(16 "In7.Cu" signal "IN2")
		(18 "In8.Cu" signal "GND3")
		(20 "In9.Cu" signal "IN3")
		(22 "In10.Cu" signal "GND4")
		(24 "In11.Cu" signal "IN4")
		(26 "In12.Cu" signal "GND5")
		(28 "In13.Cu" signal "IN5")
		(30 "In14.Cu" signal "GND6")
		(32 "In15.Cu" signal "IN6")
		(34 "In16.Cu" signal "GND7")
		(2 "B.Cu" signal "BOTTOM")
		(9 "F.Adhes" user "F.Adhesive")
		(11 "B.Adhes" user "B.Adhesive")
		(13 "F.Paste" user "Package Geometry/Pastemask Top")
		(15 "B.Paste" user "Package Geometry/Pastemask Bottom")
		(5 "F.SilkS" user "Ref Des/Silkscreen Top")
		(7 "B.SilkS" user "Ref Des/Silkscreen Bottom")
		(1 "F.Mask" user "Board Geometry/Soldermask Top")
		(3 "B.Mask" user "Board Geometry/Soldermask Bottom")
		(17 "Dwgs.User" user "User.Drawings")
		(19 "Cmts.User" user "User.Comments")
		(21 "Eco1.User" user "User.Eco1")
		(23 "Eco2.User" user "User.Eco2")
		(25 "Edge.Cuts" user "Board Geometry/Outline")
		(27 "Margin" user)
		(31 "F.CrtYd" user "Package Geometry/Place Bound Top")
		(29 "B.CrtYd" user "Package Geometry/Place Bound Bottom")
		(35 "F.Fab" user "Ref Des/Assembly Top")
		(33 "B.Fab" user "Ref Des/Assembly Bottom")
	)
	(footprint ""
		(layer "F.Cu")
		(at 142.474442 -252.356874 -90)
		(property "Reference" "R1291"
			(at 0 0 270)
			(layer "F.SilkS")
			(hide yes)
			(effects
				(font
					(size 1.27 1.27)
				)
			)
		)
		(property "Value" ""
			(at 0 0 270)
			(layer "F.Fab")
			(effects
				(font
					(size 1.27 1.27)
				)
			)
		)
		(duplicate_pad_numbers_are_jumpers no)
		(fp_line
			(start -0.7874 0.4064)
			(end -0.7874 -0.4064)
			(stroke
				(width 0.1524)
				(type default)
			)
			(layer "F.SilkS")
		)
		(fp_line
			(start 0.7874 0.4064)
			(end -0.7874 0.4064)
			(stroke
				(width 0.1524)
				(type default)
			)
			(layer "F.SilkS")
		)
		(fp_line
			(start -0.7874 -0.4064)
			(end 0.7874 -0.4064)
			(stroke
				(width 0.1524)
				(type default)
			)
			(layer "F.SilkS")
		)
		(fp_line
			(start 0.7874 -0.4064)
			(end 0.7874 0.4064)
			(stroke
				(width 0.1524)
				(type default)
			)
			(layer "F.SilkS")
		)
		(fp_line
			(start -0.67945 0.3048)
			(end -0.67945 -0.305054)
			(stroke
				(width 0.1)
				(type default)
			)
			(layer "F.Fab")
		)
		(fp_line
			(start -0.12065 0.3048)
			(end -0.67945 0.3048)
			(stroke
				(width 0.1)
				(type default)
			)
			(layer "F.Fab")
		)
		(fp_line
			(start 0.120396 0.3048)
			(end 0.120396 0.2794)
			(stroke
				(width 0.1)
				(type default)
			)
			(layer "F.Fab")
		)
		(fp_line
			(start 0.67945 0.3048)
			(end 0.120396 0.3048)
			(stroke
				(width 0.1)
				(type default)
			)
			(layer "F.Fab")
		)
		(fp_line
			(start -0.12065 0.2794)
			(end -0.12065 0.3048)
			(stroke
				(width 0.1)
				(type default)
			)
			(layer "F.Fab")
		)
		(fp_line
			(start 0.120396 0.2794)
			(end -0.12065 0.2794)
			(stroke
				(width 0.1)
				(type default)
			)
			(layer "F.Fab")
		)
		(fp_line
			(start -0.12065 -0.2794)
			(end 0.12065 -0.2794)
			(stroke
				(width 0.1)
				(type default)
			)
			(layer "F.Fab")
		)
		(fp_line
			(start 0.12065 -0.2794)
			(end 0.12065 -0.3048)
			(stroke
				(width 0.1)
				(type default)
			)
			(layer "F.Fab")
		)
		(fp_line
			(start 0.12065 -0.3048)
			(end 0.67945 -0.3048)
			(stroke
				(width 0.1)
				(type default)
			)
			(layer "F.Fab")
		)
		(fp_line
			(start 0.67945 -0.3048)
			(end 0.67945 0.3048)
			(stroke
				(width 0.1)
				(type default)
			)
			(layer "F.Fab")
		)
		(fp_line
			(start -0.67945 -0.305054)
			(end -0.12065 -0.305054)
			(stroke
				(width 0.1)
				(type default)
			)
			(layer "F.Fab")
		)
		(fp_line
			(start -0.12065 -0.305054)
			(end -0.12065 -0.2794)
			(stroke
				(width 0.1)
				(type default)
			)
			(layer "F.Fab")
		)
		(pad "1" smd circle
			(at -0.40005 0 270)
			(size 0 0)
			(layers "F.Cu" "F.Mask" "F.Paste")
			(net "GND")
		)
		(pad "2" smd circle
			(at 0.40005 0 270)
			(size 0 0)
			(layers "F.Cu" "F.Mask" "F.Paste")
			(net "PEX1_MODE_SEL2")
		)
	)
	(footprint ""
		(layer "F.Cu")
		(at 218.483434 -49.94148)
		(property "Reference" "R5897"
			(at 0 0 0)
			(layer "F.SilkS")
			(hide yes)
			(effects
				(font
					(size 1.27 1.27)
				)
			)
		)
		(property "Value" ""
			(at 0 0 0)
			(layer "F.Fab")
			(effects
				(font
					(size 1.27 1.27)
				)
			)
		)
		(duplicate_pad_numbers_are_jumpers no)
		(fp_line
			(start -0.7874 -0.4064)
			(end 0.7874 -0.4064)
			(stroke
				(width 0.1524)
				(type default)
			)
			(layer "F.SilkS")
		)
		(fp_line
			(start -0.7874 0.4064)
			(end -0.7874 -0.4064)
			(stroke
				(width 0.1524)
				(type default)
			)
			(layer "F.SilkS")
		)
		(fp_line
			(start 0.7874 -0.4064)
			(end 0.7874 0.4064)
			(stroke
				(width 0.1524)
				(type default)
			)
			(layer "F.SilkS")
		)
		(fp_line
			(start 0.7874 0.4064)
			(end -0.7874 0.4064)
			(stroke
				(width 0.1524)
				(type default)
			)
			(layer "F.SilkS")
		)
		(fp_line
			(start -0.67945 -0.305054)
			(end -0.12065 -0.305054)
			(stroke
				(width 0.1)
				(type default)
			)
			(layer "F.Fab")
		)
		(fp_line
			(start -0.67945 0.3048)
			(end -0.67945 -0.305054)
			(stroke
				(width 0.1)
				(type default)
			)
			(layer "F.Fab")
		)
		(fp_line
			(start -0.12065 -0.305054)
			(end -0.12065 -0.2794)
			(stroke
				(width 0.1)
				(type default)
			)
			(layer "F.Fab")
		)
		(fp_line
			(start -0.12065 -0.2794)
			(end 0.12065 -0.2794)
			(stroke
				(width 0.1)
				(type default)
			)
			(layer "F.Fab")
		)
		(fp_line
			(start -0.12065 0.2794)
			(end -0.12065 0.3048)
			(stroke
				(width 0.1)
				(type default)
			)
			(layer "F.Fab")
		)
		(fp_line
			(start -0.12065 0.3048)
			(end -0.67945 0.3048)
			(stroke
				(width 0.1)
				(type default)
			)
			(layer "F.Fab")
		)
		(fp_line
			(start 0.120396 0.2794)
			(end -0.12065 0.2794)
			(stroke
				(width 0.1)
				(type default)
			)
			(layer "F.Fab")
		)
		(fp_line
			(start 0.120396 0.3048)
			(end 0.120396 0.2794)
			(stroke
				(width 0.1)
				(type default)
			)
			(layer "F.Fab")
		)
		(fp_line
			(start 0.12065 -0.3048)
			(end 0.67945 -0.3048)
			(stroke
				(width 0.1)
				(type default)
			)
			(layer "F.Fab")
		)
		(fp_line
			(start 0.12065 -0.2794)
			(end 0.12065 -0.3048)
			(stroke
				(width 0.1)
				(type default)
			)
			(layer "F.Fab")
		)
		(fp_line
			(start 0.67945 -0.3048)
			(end 0.67945 0.3048)
			(stroke
				(width 0.1)
				(type default)
			)
			(layer "F.Fab")
		)
		(fp_line
			(start 0.67945 0.3048)
			(end 0.120396 0.3048)
			(stroke
				(width 0.1)
				(type default)
			)
			(layer "F.Fab")
		)
		(pad "1" smd circle
			(at -0.40005 0)
			(size 0 0)
			(layers "F.Cu" "F.Mask" "F.Paste")
			(net "SSD7_ADC_A0")
		)
		(pad "2" smd circle
			(at 0.40005 0)
			(size 0 0)
			(layers "F.Cu" "F.Mask" "F.Paste")
			(net "SMB_SSD7_ADC_SCL")
		)
	)
	(footprint ""
		(layer "F.Cu")
		(at 429.455072 -53.468524 90)
		(property "Reference" "PC571"
			(at 0 0 90)
			(layer "F.SilkS")
			(hide yes)
			(effects
				(font
					(size 1.27 1.27)
				)
			)
		)
		(property "Value" ""
			(at 0 0 90)
			(layer "F.Fab")
			(effects
				(font
					(size 1.27 1.27)
				)
			)
		)
		(duplicate_pad_numbers_are_jumpers no)
		(fp_line
			(start 1.524 -0.762)
			(end 1.524 0.762)
			(stroke
				(width 0.1524)
				(type default)
			)
			(layer "F.SilkS")
		)
		(fp_line
			(start -1.524 -0.762)
			(end 1.524 -0.762)
			(stroke
				(width 0.1524)
				(type default)
			)
			(layer "F.SilkS")
		)
		(fp_line
			(start 1.524 0.762)
			(end -1.524 0.762)
			(stroke
				(width 0.1524)
				(type default)
			)
			(layer "F.SilkS")
		)
		(fp_line
			(start -1.524 0.762)
			(end -1.524 -0.762)
			(stroke
				(width 0.1524)
				(type default)
			)
			(layer "F.SilkS")
		)
		(fp_line
			(start 1.1049 -0.724916)
			(end -1.1049 -0.724916)
			(stroke
				(width 0.1)
				(type default)
			)
			(layer "F.Fab")
		)
		(fp_line
			(start -1.1049 -0.724916)
			(end -1.1049 0.724916)
			(stroke
				(width 0.1)
				(type default)
			)
			(layer "F.Fab")
		)
		(fp_line
			(start 1.1049 0.724916)
			(end 1.1049 -0.724916)
			(stroke
				(width 0.1)
				(type default)
			)
			(layer "F.Fab")
		)
		(fp_line
			(start -1.1049 0.724916)
			(end 1.1049 0.724916)
			(stroke
				(width 0.1)
				(type default)
			)
			(layer "F.Fab")
		)
		(pad "1" smd rect
			(at -0.889 0 270)
			(size 1.016 1.27)
			(layers "F.Cu" "F.Mask" "F.Paste")
			(net "GND")
		)
		(pad "2" smd rect
			(at 0.889 0 270)
			(size 1.016 1.27)
			(layers "F.Cu" "F.Mask" "F.Paste")
			(net "P3V3_AUX")
		)
	)
	(footprint ""
		(layer "F.Cu")
		(at 81.883504 -61.487812 180)
		(property "Reference" "R5849"
			(at 0 0 180)
			(layer "F.SilkS")
			(hide yes)
			(effects
				(font
					(size 1.27 1.27)
				)
			)
		)
		(property "Value" ""
			(at 0 0 180)
			(layer "F.Fab")
			(effects
				(font
					(size 1.27 1.27)
				)
			)
		)
		(duplicate_pad_numbers_are_jumpers no)
		(fp_line
			(start 0.7874 0.4064)
			(end -0.7874 0.4064)
			(stroke
				(width 0.1524)
				(type default)
			)
			(layer "F.SilkS")
		)
		(fp_line
			(start 0.7874 -0.4064)
			(end 0.7874 0.4064)
			(stroke
				(width 0.1524)
				(type default)
			)
			(layer "F.SilkS")
		)
		(fp_line
			(start -0.7874 0.4064)
			(end -0.7874 -0.4064)
			(stroke
				(width 0.1524)
				(type default)
			)
			(layer "F.SilkS")
		)
		(fp_line
			(start -0.7874 -0.4064)
			(end 0.7874 -0.4064)
			(stroke
				(width 0.1524)
				(type default)
			)
			(layer "F.SilkS")
		)
		(fp_line
			(start 0.67945 0.3048)
			(end 0.120396 0.3048)
			(stroke
				(width 0.1)
				(type default)
			)
			(layer "F.Fab")
		)
		(fp_line
			(start 0.67945 -0.3048)
			(end 0.67945 0.3048)
			(stroke
				(width 0.1)
				(type default)
			)
			(layer "F.Fab")
		)
		(fp_line
			(start 0.12065 -0.2794)
			(end 0.12065 -0.3048)
			(stroke
				(width 0.1)
				(type default)
			)
			(layer "F.Fab")
		)
		(fp_line
			(start 0.12065 -0.3048)
			(end 0.67945 -0.3048)
			(stroke
				(width 0.1)
				(type default)
			)
			(layer "F.Fab")
		)
		(fp_line
			(start 0.120396 0.3048)
			(end 0.120396 0.2794)
			(stroke
				(width 0.1)
				(type default)
			)
			(layer "F.Fab")
		)
		(fp_line
			(start 0.120396 0.2794)
			(end -0.12065 0.2794)
			(stroke
				(width 0.1)
				(type default)
			)
			(layer "F.Fab")
		)
		(fp_line
			(start -0.12065 0.3048)
			(end -0.67945 0.3048)
			(stroke
				(width 0.1)
				(type default)
			)
			(layer "F.Fab")
		)
		(fp_line
			(start -0.12065 0.2794)
			(end -0.12065 0.3048)
			(stroke
				(width 0.1)
				(type default)
			)
			(layer "F.Fab")
		)
		(fp_line
			(start -0.12065 -0.2794)
			(end 0.12065 -0.2794)
			(stroke
				(width 0.1)
				(type default)
			)
			(layer "F.Fab")
		)
		(fp_line
			(start -0.12065 -0.305054)
			(end -0.12065 -0.2794)
			(stroke
				(width 0.1)
				(type default)
			)
			(layer "F.Fab")
		)
		(fp_line
			(start -0.67945 0.3048)
			(end -0.67945 -0.305054)
			(stroke
				(width 0.1)
				(type default)
			)
			(layer "F.Fab")
		)
		(fp_line
			(start -0.67945 -0.305054)
			(end -0.12065 -0.305054)
			(stroke
				(width 0.1)
				(type default)
			)
			(layer "F.Fab")
		)
		(pad "1" smd circle
			(at -0.40005 0 180)
			(size 0 0)
			(layers "F.Cu" "F.Mask" "F.Paste")
			(net "PWRGD_P12V_SSD3_D")
		)
		(pad "2" smd circle
			(at 0.40005 0 180)
			(size 0 0)
			(layers "F.Cu" "F.Mask" "F.Paste")
			(net "PWRGD_P12V_SSD3_R")
		)
	)
	(footprint ""
		(layer "F.Cu")
		(at 410.809948 -165.670484 -90)
		(property "Reference" "R2470"
			(at 0 0 270)
			(layer "F.SilkS")
			(hide yes)
			(effects
				(font
					(size 1.27 1.27)
				)
			)
		)
		(property "Value" ""
			(at 0 0 270)
			(layer "F.Fab")
			(effects
				(font
					(size 1.27 1.27)
				)
			)
		)
		(duplicate_pad_numbers_are_jumpers no)
		(fp_line
			(start -0.7874 0.4064)
			(end -0.7874 -0.4064)
			(stroke
				(width 0.1524)
				(type default)
			)
			(layer "F.SilkS")
		)
		(fp_line
			(start 0.7874 0.4064)
			(end -0.7874 0.4064)
			(stroke
				(width 0.1524)
				(type default)
			)
			(layer "F.SilkS")
		)
		(fp_line
			(start -0.7874 -0.4064)
			(end 0.7874 -0.4064)
			(stroke
				(width 0.1524)
				(type default)
			)
			(layer "F.SilkS")
		)
		(fp_line
			(start 0.7874 -0.4064)
			(end 0.7874 0.4064)
			(stroke
				(width 0.1524)
				(type default)
			)
			(layer "F.SilkS")
		)
		(fp_line
			(start -0.67945 0.3048)
			(end -0.67945 -0.305054)
			(stroke
				(width 0.1)
				(type default)
			)
			(layer "F.Fab")
		)
		(fp_line
			(start -0.12065 0.3048)
			(end -0.67945 0.3048)
			(stroke
				(width 0.1)
				(type default)
			)
			(layer "F.Fab")
		)
		(fp_line
			(start 0.120396 0.3048)
			(end 0.120396 0.2794)
			(stroke
				(width 0.1)
				(type default)
			)
			(layer "F.Fab")
		)
		(fp_line
			(start 0.67945 0.3048)
			(end 0.120396 0.3048)
			(stroke
				(width 0.1)
				(type default)
			)
			(layer "F.Fab")
		)
		(fp_line
			(start -0.12065 0.2794)
			(end -0.12065 0.3048)
			(stroke
				(width 0.1)
				(type default)
			)
			(layer "F.Fab")
		)
		(fp_line
			(start 0.120396 0.2794)
			(end -0.12065 0.2794)
			(stroke
				(width 0.1)
				(type default)
			)
			(layer "F.Fab")
		)
		(fp_line
			(start -0.12065 -0.2794)
			(end 0.12065 -0.2794)
			(stroke
				(width 0.1)
				(type default)
			)
			(layer "F.Fab")
		)
		(fp_line
			(start 0.12065 -0.2794)
			(end 0.12065 -0.3048)
			(stroke
				(width 0.1)
				(type default)
			)
			(layer "F.Fab")
		)
		(fp_line
			(start 0.12065 -0.3048)
			(end 0.67945 -0.3048)
			(stroke
				(width 0.1)
				(type default)
			)
			(layer "F.Fab")
		)
		(fp_line
			(start 0.67945 -0.3048)
			(end 0.67945 0.3048)
			(stroke
				(width 0.1)
				(type default)
			)
			(layer "F.Fab")
		)
		(fp_line
			(start -0.67945 -0.305054)
			(end -0.12065 -0.305054)
			(stroke
				(width 0.1)
				(type default)
			)
			(layer "F.Fab")
		)
		(fp_line
			(start -0.12065 -0.305054)
			(end -0.12065 -0.2794)
			(stroke
				(width 0.1)
				(type default)
			)
			(layer "F.Fab")
		)
		(pad "1" smd circle
			(at -0.40005 0 270)
			(size 0 0)
			(layers "F.Cu" "F.Mask" "F.Paste")
			(net "NIC6_PWRBRK_R_N")
		)
		(pad "2" smd circle
			(at 0.40005 0 270)
			(size 0 0)
			(layers "F.Cu" "F.Mask" "F.Paste")
			(net "NIC6_PWRBRK_N")
		)
	)
	(footprint ""
		(layer "F.Cu")
		(at 60.11037 -63.652146 180)
		(property "Reference" "R5850"
			(at 0 0 180)
			(layer "F.SilkS")
			(hide yes)
			(effects
				(font
					(size 1.27 1.27)
				)
			)
		)
		(property "Value" ""
			(at 0 0 180)
			(layer "F.Fab")
			(effects
				(font
					(size 1.27 1.27)
				)
			)
		)
		(duplicate_pad_numbers_are_jumpers no)
		(fp_line
			(start 0.7874 0.4064)
			(end -0.7874 0.4064)
			(stroke
				(width 0.1524)
				(type default)
			)
			(layer "F.SilkS")
		)
		(fp_line
			(start 0.7874 -0.4064)
			(end 0.7874 0.4064)
			(stroke
				(width 0.1524)
				(type default)
			)
			(layer "F.SilkS")
		)
		(fp_line
			(start -0.7874 0.4064)
			(end -0.7874 -0.4064)
			(stroke
				(width 0.1524)
				(type default)
			)
			(layer "F.SilkS")
		)
		(fp_line
			(start -0.7874 -0.4064)
			(end 0.7874 -0.4064)
			(stroke
				(width 0.1524)
				(type default)
			)
			(layer "F.SilkS")
		)
		(fp_line
			(start 0.67945 0.3048)
			(end 0.120396 0.3048)
			(stroke
				(width 0.1)
				(type default)
			)
			(layer "F.Fab")
		)
		(fp_line
			(start 0.67945 -0.3048)
			(end 0.67945 0.3048)
			(stroke
				(width 0.1)
				(type default)
			)
			(layer "F.Fab")
		)
		(fp_line
			(start 0.12065 -0.2794)
			(end 0.12065 -0.3048)
			(stroke
				(width 0.1)
				(type default)
			)
			(layer "F.Fab")
		)
		(fp_line
			(start 0.12065 -0.3048)
			(end 0.67945 -0.3048)
			(stroke
				(width 0.1)
				(type default)
			)
			(layer "F.Fab")
		)
		(fp_line
			(start 0.120396 0.3048)
			(end 0.120396 0.2794)
			(stroke
				(width 0.1)
				(type default)
			)
			(layer "F.Fab")
		)
		(fp_line
			(start 0.120396 0.2794)
			(end -0.12065 0.2794)
			(stroke
				(width 0.1)
				(type default)
			)
			(layer "F.Fab")
		)
		(fp_line
			(start -0.12065 0.3048)
			(end -0.67945 0.3048)
			(stroke
				(width 0.1)
				(type default)
			)
			(layer "F.Fab")
		)
		(fp_line
			(start -0.12065 0.2794)
			(end -0.12065 0.3048)
			(stroke
				(width 0.1)
				(type default)
			)
			(layer "F.Fab")
		)
		(fp_line
			(start -0.12065 -0.2794)
			(end 0.12065 -0.2794)
			(stroke
				(width 0.1)
				(type default)
			)
			(layer "F.Fab")
		)
		(fp_line
			(start -0.12065 -0.305054)
			(end -0.12065 -0.2794)
			(stroke
				(width 0.1)
				(type default)
			)
			(layer "F.Fab")
		)
		(fp_line
			(start -0.67945 0.3048)
			(end -0.67945 -0.305054)
			(stroke
				(width 0.1)
				(type default)
			)
			(layer "F.Fab")
		)
		(fp_line
			(start -0.67945 -0.305054)
			(end -0.12065 -0.305054)
			(stroke
				(width 0.1)
				(type default)
			)
			(layer "F.Fab")
		)
		(pad "1" smd circle
			(at -0.40005 0 180)
			(size 0 0)
			(layers "F.Cu" "F.Mask" "F.Paste")
			(net "P5V_AUX")
		)
		(pad "2" smd circle
			(at 0.40005 0 180)
			(size 0 0)
			(layers "F.Cu" "F.Mask" "F.Paste")
			(net "P12V_SSD2_PG_G2")
		)
	)
	(footprint ""
		(layer "F.Cu")
		(at 428.319438 -129.880106 180)
		(property "Reference" "C657"
			(at 0 0 180)
			(layer "F.SilkS")
			(hide yes)
			(effects
				(font
					(size 1.27 1.27)
				)
			)
		)
		(property "Value" ""
			(at 0 0 180)
			(layer "F.Fab")
			(effects
				(font
					(size 1.27 1.27)
				)
			)
		)
		(duplicate_pad_numbers_are_jumpers no)
		(fp_line
			(start 0.299974 0.150114)
			(end -0.299974 0.150114)
			(stroke
				(width 0.1)
				(type default)
			)
			(layer "F.Fab")
		)
		(fp_line
			(start 0.299974 -0.150114)
			(end 0.299974 0.150114)
			(stroke
				(width 0.1)
				(type default)
			)
			(layer "F.Fab")
		)
		(fp_line
			(start -0.299974 0.150114)
			(end -0.299974 -0.150114)
			(stroke
				(width 0.1)
				(type default)
			)
			(layer "F.Fab")
		)
		(fp_line
			(start -0.299974 -0.150114)
			(end 0.299974 -0.150114)
			(stroke
				(width 0.1)
				(type default)
			)
			(layer "F.Fab")
		)
		(pad "1" smd rect
			(at -0.2667 0 180)
			(size 0.3048 0.381)
			(layers "F.Cu" "F.Mask" "F.Paste")
			(net "P5E_PEX3_STN0_TX_DN<4>")
		)
		(pad "2" smd rect
			(at 0.2667 0 180)
			(size 0.3048 0.381)
			(layers "F.Cu" "F.Mask" "F.Paste")
			(net "P5E_PEX3_STN0_TX_C_DN<4>")
		)
	)
)
